(kicad_pcb
	(version 20241229)
	(generator "pcbnew")
	(generator_version "9.0")
	(general
		(thickness 1.711)
		(legacy_teardrops no)
	)
	(paper "A4")
	(title_block
		(title "Antmicro Baseboard for Jetson AGX Thor")
		(date "2026-02-18")
		(rev "1.1.0")
		(company "Antmicro Ltd")
		(comment 1 "www.antmicro.com")
		(comment 9 "footprints 1150-1154 of 1170")
	)
	(layers
		(0 "F.Cu" signal)
		(4 "In1.Cu" signal)
		(6 "In2.Cu" signal)
		(8 "In3.Cu" signal)
		(10 "In4.Cu" jumper)
		(12 "In5.Cu" signal)
		(14 "In6.Cu" signal)
		(16 "In7.Cu" signal)
		(18 "In8.Cu" signal)
		(2 "B.Cu" signal)
		(9 "F.Adhes" user "F.Adhesive")
		(11 "B.Adhes" user "B.Adhesive")
		(13 "F.Paste" user)
		(15 "B.Paste" user)
		(5 "F.SilkS" user "F.Silkscreen")
		(7 "B.SilkS" user "B.Silkscreen")
		(1 "F.Mask" user)
		(3 "B.Mask" user)
		(17 "Dwgs.User" user "User.Drawings")
		(19 "Cmts.User" user "User.Comments")
		(21 "Eco1.User" user "User.Eco1")
		(23 "Eco2.User" user "User.Eco2")
		(25 "Edge.Cuts" user)
		(27 "Margin" user)
		(31 "F.CrtYd" user "F.Courtyard")
		(29 "B.CrtYd" user "B.Courtyard")
		(35 "F.Fab" user)
		(33 "B.Fab" user)
	)
	(footprint "antmicro-footprints:R_0402_1005Metric"
		(layer "B.Cu")
		(at 217.04 109.48)
		(descr "Resistor SMD 0402")
		(tags "resistor SMD 0402")
		(property "Reference" "R303"
			(at -1.34 -1.38 0)
			(layer "B.SilkS")
			(effects
				(font
					(size 0.7 0.7)
					(thickness 0.15)
				)
				(justify right top mirror)
			)
		)
		(property "Value" "R_10k_0402"
			(at -1.011843 -1.772047 0)
			(layer "B.Fab")
			(effects
				(font
					(size 0.7 0.7)
					(thickness 0.15)
				)
				(justify right top mirror)
			)
		)
		(property "Datasheet" "https://www.bourns.com/docs/product-datasheets/cr.pdf"
			(at 0 0 0)
			(layer "B.Fab")
			(hide yes)
			(effects
				(font
					(size 1.27 1.27)
					(thickness 0.15)
				)
				(justify mirror)
			)
		)
		(property "Description" "SMD Chip Resistor, 10 kohm, ± 1%, 62.5 mW, 0402 [1005 Metric], Thick Film, General Purpose"
			(at 0 0 0)
			(layer "B.Fab")
			(hide yes)
			(effects
				(font
					(size 1.27 1.27)
					(thickness 0.15)
				)
				(justify mirror)
			)
		)
		(property "MPN" "CR0402-FX-1002GLF"
			(at 0 0 180)
			(unlocked yes)
			(layer "B.Fab")
			(hide yes)
			(effects
				(font
					(size 1 1)
					(thickness 0.15)
				)
				(justify mirror)
			)
		)
		(property "Manufacturer" "Bourns"
			(at 0 0 180)
			(unlocked yes)
			(layer "B.Fab")
			(hide yes)
			(effects
				(font
					(size 1 1)
					(thickness 0.15)
				)
				(justify mirror)
			)
		)
		(property "License" "Apache-2.0"
			(at 0 0 180)
			(unlocked yes)
			(layer "B.Fab")
			(hide yes)
			(effects
				(font
					(size 1 1)
					(thickness 0.15)
				)
				(justify mirror)
			)
		)
		(property "Author" "Antmicro"
			(at 0 0 180)
			(unlocked yes)
			(layer "B.Fab")
			(hide yes)
			(effects
				(font
					(size 1 1)
					(thickness 0.15)
				)
				(justify mirror)
			)
		)
		(property "Val" "10k"
			(at 0 0 180)
			(unlocked yes)
			(layer "B.Fab")
			(hide yes)
			(effects
				(font
					(size 1 1)
					(thickness 0.15)
				)
				(justify mirror)
			)
		)
		(property "Tolerance" "1%"
			(at 0 0 180)
			(unlocked yes)
			(layer "B.Fab")
			(hide yes)
			(effects
				(font
					(size 1 1)
					(thickness 0.15)
				)
				(justify mirror)
			)
		)
		(sheetname "/USB Hub/")
		(sheetfile "usb_hub.kicad_sch")
		(attr smd)
		(fp_rect
			(start -0.925 0.47)
			(end 0.925 -0.47)
			(stroke
				(width 0.05)
				(type default)
			)
			(fill no)
			(layer "B.CrtYd")
		)
		(fp_rect
			(start -0.5 0.25)
			(end 0.5 -0.25)
			(stroke
				(width 0.15)
				(type solid)
			)
			(fill no)
			(layer "B.Fab")
		)
		(fp_text user "License: Apache-2.0"
			(at -0.95 -5.169 0)
			(layer "B.Fab")
			(effects
				(font
					(size 0.7 0.7)
					(thickness 0.15)
				)
				(justify right top mirror)
			)
		)
		(fp_text user "${REFERENCE}"
			(at -0.95 -3.168 0)
			(layer "B.Fab")
			(effects
				(font
					(size 0.7 0.7)
					(thickness 0.15)
				)
				(justify right top mirror)
			)
		)
		(fp_text user "Author: Antmicro"
			(at -0.95 -4.169 0)
			(layer "B.Fab")
			(effects
				(font
					(size 0.7 0.7)
					(thickness 0.15)
				)
				(justify right top mirror)
			)
		)
		(pad "1" smd roundrect
			(at -0.48 0)
			(size 0.59 0.64)
			(layers "B.Cu" "B.Mask" "B.Paste")
			(roundrect_rratio 0.25)
			(net 5 "+5V")
			(pintype "passive")
		)
		(pad "2" smd roundrect
			(at 0.48 0)
			(size 0.59 0.64)
			(layers "B.Cu" "B.Mask" "B.Paste")
			(roundrect_rratio 0.25)
			(net 1331 "Net-(Q26-D1)")
			(pintype "passive")
		)
	)
	(footprint "antmicro-footprints:TP_SMD_0.75mm"
		(layer "B.Cu")
		(at 185.39 58 180)
		(property "Reference" "TP128"
			(at -0.45 4.02 270)
			(layer "B.SilkS")
			(effects
				(font
					(size 0.7 0.7)
					(thickness 0.15)
				)
				(justify left bottom mirror)
			)
		)
		(property "Value" "TP_0.75mm_SMD"
			(at 0 -1.2 0)
			(layer "B.Fab")
			(effects
				(font
					(size 0.7 0.7)
					(thickness 0.15)
				)
				(justify left bottom mirror)
			)
		)
		(property "Description" "SMT test point"
			(at 0 0 0)
			(layer "B.Fab")
			(hide yes)
			(effects
				(font
					(size 1.27 1.27)
					(thickness 0.15)
				)
				(justify mirror)
			)
		)
		(property "MPN" ""
			(at 0 0 0)
			(unlocked yes)
			(layer "B.Fab")
			(hide yes)
			(effects
				(font
					(size 1 1)
					(thickness 0.15)
				)
				(justify mirror)
			)
		)
		(property "Manufacturer" ""
			(at 0 0 0)
			(unlocked yes)
			(layer "B.Fab")
			(hide yes)
			(effects
				(font
					(size 1 1)
					(thickness 0.15)
				)
				(justify mirror)
			)
		)
		(property "Author" "Antmicro"
			(at 0 0 0)
			(unlocked yes)
			(layer "B.Fab")
			(hide yes)
			(effects
				(font
					(size 1 1)
					(thickness 0.15)
				)
				(justify mirror)
			)
		)
		(property "License" "Apache-2.0"
			(at 0 0 0)
			(unlocked yes)
			(layer "B.Fab")
			(hide yes)
			(effects
				(font
					(size 1 1)
					(thickness 0.15)
				)
				(justify mirror)
			)
		)
		(sheetname "/Power/")
		(sheetfile "power.kicad_sch")
		(attr exclude_from_pos_files exclude_from_bom)
		(fp_circle
			(center 0 0)
			(end 0.475 0)
			(stroke
				(width 0.05)
				(type default)
			)
			(fill no)
			(layer "B.CrtYd")
		)
		(fp_text user "Author: Antmicro"
			(at -0.4 -3.901 0)
			(layer "B.Fab")
			(effects
				(font
					(size 0.7 0.7)
					(thickness 0.15)
				)
				(justify left bottom mirror)
			)
		)
		(fp_text user "${REFERENCE}"
			(at -0.4 -2.7 0)
			(layer "B.Fab")
			(effects
				(font
					(size 0.7 0.7)
					(thickness 0.15)
				)
				(justify left bottom mirror)
			)
		)
		(fp_text user "License: Apache-2.0"
			(at -0.4 -5.101 0)
			(layer "B.Fab")
			(effects
				(font
					(size 0.7 0.7)
					(thickness 0.15)
				)
				(justify left bottom mirror)
			)
		)
		(pad "1" smd circle
			(at 0 0 180)
			(size 0.75 0.75)
			(layers "B.Cu" "B.Mask")
			(net 13 "VCC")
			(pinfunction "1")
			(pintype "passive")
		)
	)
	(footprint "antmicro-footprints:R_0402_1005Metric"
		(layer "B.Cu")
		(at 178.3 67.4 180)
		(descr "Resistor SMD 0402")
		(tags "resistor SMD 0402")
		(property "Reference" "R34"
			(at -1.1 -1.4 0)
			(layer "B.SilkS")
			(effects
				(font
					(size 0.7 0.7)
					(thickness 0.15)
				)
				(justify left bottom mirror)
			)
		)
		(property "Value" "R_49k9_0402"
			(at -1.011843 -1.772047 0)
			(layer "B.Fab")
			(effects
				(font
					(size 0.7 0.7)
					(thickness 0.15)
				)
				(justify left bottom mirror)
			)
		)
		(property "Datasheet" "https://www.bourns.com/docs/product-datasheets/cr.pdf"
			(at 0 0 0)
			(layer "B.Fab")
			(hide yes)
			(effects
				(font
					(size 1.27 1.27)
					(thickness 0.15)
				)
				(justify mirror)
			)
		)
		(property "Description" "SMD Chip Resistor, 49.9 kohm, ± 1%, 63 mW, 0402 [1005 Metric], Thick Film, General Purpose"
			(at 0 0 0)
			(layer "B.Fab")
			(hide yes)
			(effects
				(font
					(size 1.27 1.27)
					(thickness 0.15)
				)
				(justify mirror)
			)
		)
		(property "MPN" "CR0402-FX-4992GLF"
			(at 0 0 0)
			(unlocked yes)
			(layer "B.Fab")
			(hide yes)
			(effects
				(font
					(size 1 1)
					(thickness 0.15)
				)
				(justify mirror)
			)
		)
		(property "Manufacturer" "Bourns"
			(at 0 0 0)
			(unlocked yes)
			(layer "B.Fab")
			(hide yes)
			(effects
				(font
					(size 1 1)
					(thickness 0.15)
				)
				(justify mirror)
			)
		)
		(property "License" "Apache-2.0"
			(at 0 0 0)
			(unlocked yes)
			(layer "B.Fab")
			(hide yes)
			(effects
				(font
					(size 1 1)
					(thickness 0.15)
				)
				(justify mirror)
			)
		)
		(property "Author" "Antmicro"
			(at 0 0 0)
			(unlocked yes)
			(layer "B.Fab")
			(hide yes)
			(effects
				(font
					(size 1 1)
					(thickness 0.15)
				)
				(justify mirror)
			)
		)
		(property "Val" "49k9"
			(at 0 0 0)
			(unlocked yes)
			(layer "B.Fab")
			(hide yes)
			(effects
				(font
					(size 1 1)
					(thickness 0.15)
				)
				(justify mirror)
			)
		)
		(property "Tolerance" "1%"
			(at 0 0 0)
			(unlocked yes)
			(layer "B.Fab")
			(hide yes)
			(effects
				(font
					(size 1 1)
					(thickness 0.15)
				)
				(justify mirror)
			)
		)
		(component_classes
			(class "DCDC_20V")
		)
		(sheetname "/DCDC/")
		(sheetfile "dcdc.kicad_sch")
		(attr smd exclude_from_pos_files exclude_from_bom dnp)
		(fp_rect
			(start -0.925 0.47)
			(end 0.925 -0.47)
			(stroke
				(width 0.05)
				(type default)
			)
			(fill no)
			(layer "B.CrtYd")
		)
		(fp_rect
			(start -0.5 0.25)
			(end 0.5 -0.25)
			(stroke
				(width 0.15)
				(type solid)
			)
			(fill no)
			(layer "B.Fab")
		)
		(fp_text user "${REFERENCE}"
			(at -0.95 -3.168 0)
			(layer "B.Fab")
			(effects
				(font
					(size 0.7 0.7)
					(thickness 0.15)
				)
				(justify left bottom mirror)
			)
		)
		(fp_text user "License: Apache-2.0"
			(at -0.95 -5.169 0)
			(layer "B.Fab")
			(effects
				(font
					(size 0.7 0.7)
					(thickness 0.15)
				)
				(justify left bottom mirror)
			)
		)
		(fp_text user "Author: Antmicro"
			(at -0.95 -4.169 0)
			(layer "B.Fab")
			(effects
				(font
					(size 0.7 0.7)
					(thickness 0.15)
				)
				(justify left bottom mirror)
			)
		)
		(pad "1" smd roundrect
			(at -0.48 0 180)
			(size 0.59 0.64)
			(layers "B.Cu" "B.Mask" "B.Paste")
			(roundrect_rratio 0.25)
			(net 1211 "/DCDC/20V_EN")
			(pintype "passive")
		)
		(pad "2" smd roundrect
			(at 0.48 0 180)
			(size 0.59 0.64)
			(layers "B.Cu" "B.Mask" "B.Paste")
			(roundrect_rratio 0.25)
			(net 4 "+3V3_AON")
			(pintype "passive")
		)
	)
	(footprint "antmicro-footprints:R_0402_1005Metric"
		(layer "B.Cu")
		(at 205.4 105.800001 180)
		(descr "Resistor SMD 0402")
		(tags "resistor SMD 0402")
		(property "Reference" "R279"
			(at -6.5 -0.399999 0)
			(layer "B.SilkS")
			(effects
				(font
					(size 0.7 0.7)
					(thickness 0.15)
				)
				(justify left bottom mirror)
			)
		)
		(property "Value" "R_200k_0402"
			(at -1.011843 -1.772046 0)
			(layer "B.Fab")
			(effects
				(font
					(size 0.7 0.7)
					(thickness 0.15)
				)
				(justify left bottom mirror)
			)
		)
		(property "Datasheet" "https://www.bourns.com/docs/product-datasheets/cr.pdf"
			(at 0 0 0)
			(layer "B.Fab")
			(hide yes)
			(effects
				(font
					(size 1.27 1.27)
					(thickness 0.15)
				)
				(justify mirror)
			)
		)
		(property "Description" "SMD Chip Resistor, 200 kohm, ± 1%, 62.5 mW, 0402 [1005 Metric], Thick Film, General Purpose"
			(at 0 0 0)
			(layer "B.Fab")
			(hide yes)
			(effects
				(font
					(size 1.27 1.27)
					(thickness 0.15)
				)
				(justify mirror)
			)
		)
		(property "Manufacturer" "Bourns"
			(at 0 0 0)
			(unlocked yes)
			(layer "B.Fab")
			(hide yes)
			(effects
				(font
					(size 1 1)
					(thickness 0.15)
				)
				(justify mirror)
			)
		)
		(property "MPN" "CR0402-FX-2003GLF"
			(at 0 0 0)
			(unlocked yes)
			(layer "B.Fab")
			(hide yes)
			(effects
				(font
					(size 1 1)
					(thickness 0.15)
				)
				(justify mirror)
			)
		)
		(property "Val" "200k"
			(at 0 0 0)
			(unlocked yes)
			(layer "B.Fab")
			(hide yes)
			(effects
				(font
					(size 1 1)
					(thickness 0.15)
				)
				(justify mirror)
			)
		)
		(property "License" "Apache-2.0"
			(at 0 0 0)
			(unlocked yes)
			(layer "B.Fab")
			(hide yes)
			(effects
				(font
					(size 1 1)
					(thickness 0.15)
				)
				(justify mirror)
			)
		)
		(property "Author" "Antmicro"
			(at 0 0 0)
			(unlocked yes)
			(layer "B.Fab")
			(hide yes)
			(effects
				(font
					(size 1 1)
					(thickness 0.15)
				)
				(justify mirror)
			)
		)
		(property "Tolerance" "1%"
			(at 0 0 0)
			(unlocked yes)
			(layer "B.Fab")
			(hide yes)
			(effects
				(font
					(size 1 1)
					(thickness 0.15)
				)
				(justify mirror)
			)
		)
		(sheetname "/Recovery USB/")
		(sheetfile "recovery_usb.kicad_sch")
		(attr smd)
		(fp_poly
			(pts
				(xy -0.925 0.47) (xy -0.925 -0.47) (xy 0.925 -0.47) (xy 0.925 0.47)
			)
			(stroke
				(width 0.05)
				(type default)
			)
			(fill no)
			(layer "B.CrtYd")
		)
		(fp_poly
			(pts
				(xy -0.5 0.25) (xy -0.5 -0.25) (xy 0.5 -0.25) (xy 0.5 0.25)
			)
			(stroke
				(width 0.15)
				(type solid)
			)
			(fill no)
			(layer "B.Fab")
		)
		(fp_text user "License: Apache-2.0"
			(at -0.949999 -5.169 0)
			(layer "B.Fab")
			(effects
				(font
					(size 0.7 0.7)
					(thickness 0.15)
				)
				(justify left bottom mirror)
			)
		)
		(fp_text user "Author: Antmicro"
			(at -0.95 -4.169 0)
			(layer "B.Fab")
			(effects
				(font
					(size 0.7 0.7)
					(thickness 0.15)
				)
				(justify left bottom mirror)
			)
		)
		(fp_text user "${REFERENCE}"
			(at -0.95 -3.168 0)
			(layer "B.Fab")
			(effects
				(font
					(size 0.7 0.7)
					(thickness 0.15)
				)
				(justify left bottom mirror)
			)
		)
		(pad "1" smd roundrect
			(at -0.48 0 180)
			(size 0.59 0.64)
			(layers "B.Cu" "B.Mask" "B.Paste")
			(roundrect_rratio 0.25)
			(net 2 "+3V3")
			(pintype "passive")
		)
		(pad "2" smd roundrect
			(at 0.48 0 180)
			(size 0.59 0.64)
			(layers "B.Cu" "B.Mask" "B.Paste")
			(roundrect_rratio 0.25)
			(net 1024 "/Recovery USB/USBC2_I2C_SDA")
			(pintype "passive")
		)
	)
	(footprint "antmicro-footprints:R_0402_1005Metric"
		(layer "B.Cu")
		(at 199.6 70.6 -90)
		(descr "Resistor SMD 0402")
		(tags "resistor SMD 0402")
		(property "Reference" "R111"
			(at -1.2 -1.5 90)
			(layer "B.SilkS")
			(effects
				(font
					(size 0.7 0.7)
					(thickness 0.15)
				)
				(justify left bottom mirror)
			)
		)
		(property "Value" "R_0R_0402"
			(at -1.011843 -1.772046 90)
			(layer "B.Fab")
			(effects
				(font
					(size 0.7 0.7)
					(thickness 0.15)
				)
				(justify left bottom mirror)
			)
		)
		(property "Datasheet" "https://industrial.panasonic.com/cdbs/www-data/pdf/RDA0000/AOA0000C301.pdf"
			(at 0 0 90)
			(layer "B.Fab")
			(hide yes)
			(effects
				(font
					(size 1.27 1.27)
					(thickness 0.15)
				)
				(justify mirror)
			)
		)
		(property "Description" "SMD Chip Resistor, Jumper, 0 ohm, 100 mW, 0402 [1005 Metric], Thick Film, General Purpose"
			(at 0 0 90)
			(layer "B.Fab")
			(hide yes)
			(effects
				(font
					(size 1.27 1.27)
					(thickness 0.15)
				)
				(justify mirror)
			)
		)
		(property "Manufacturer" "Panasonic"
			(at 0 0 90)
			(unlocked yes)
			(layer "B.Fab")
			(hide yes)
			(effects
				(font
					(size 1 1)
					(thickness 0.15)
				)
				(justify mirror)
			)
		)
		(property "MPN" "ERJ2GE0R00X"
			(at 0 0 90)
			(unlocked yes)
			(layer "B.Fab")
			(hide yes)
			(effects
				(font
					(size 1 1)
					(thickness 0.15)
				)
				(justify mirror)
			)
		)
		(property "Val" "0R"
			(at 0 0 90)
			(unlocked yes)
			(layer "B.Fab")
			(hide yes)
			(effects
				(font
					(size 1 1)
					(thickness 0.15)
				)
				(justify mirror)
			)
		)
		(property "License" "Apache-2.0"
			(at 0 0 90)
			(unlocked yes)
			(layer "B.Fab")
			(hide yes)
			(effects
				(font
					(size 1 1)
					(thickness 0.15)
				)
				(justify mirror)
			)
		)
		(property "Author" "Antmicro"
			(at 0 0 90)
			(unlocked yes)
			(layer "B.Fab")
			(hide yes)
			(effects
				(font
					(size 1 1)
					(thickness 0.15)
				)
				(justify mirror)
			)
		)
		(property "Tolerance" "~"
			(at 0 0 90)
			(unlocked yes)
			(layer "B.Fab")
			(hide yes)
			(effects
				(font
					(size 1 1)
					(thickness 0.15)
				)
				(justify mirror)
			)
		)
		(property "Current" "1A"
			(at 0 0 90)
			(unlocked yes)
			(layer "B.Fab")
			(hide yes)
			(effects
				(font
					(size 1 1)
					(thickness 0.15)
				)
				(justify mirror)
			)
		)
		(sheetname "/USB Debug, PD/")
		(sheetfile "usb_debug_pd.kicad_sch")
		(attr smd)
		(fp_poly
			(pts
				(xy -0.925 0.47) (xy 0.925 0.47) (xy 0.925 -0.47) (xy -0.925 -0.47)
			)
			(stroke
				(width 0.05)
				(type default)
			)
			(fill no)
			(layer "B.CrtYd")
		)
		(fp_poly
			(pts
				(xy -0.5 0.25) (xy 0.5 0.25) (xy 0.5 -0.25) (xy -0.5 -0.25)
			)
			(stroke
				(width 0.15)
				(type solid)
			)
			(fill no)
			(layer "B.Fab")
		)
		(fp_text user "Author: Antmicro"
			(at -0.95 -4.169 90)
			(layer "B.Fab")
			(effects
				(font
					(size 0.7 0.7)
					(thickness 0.15)
				)
				(justify left bottom mirror)
			)
		)
		(fp_text user "License: Apache-2.0"
			(at -0.949999 -5.169 90)
			(layer "B.Fab")
			(effects
				(font
					(size 0.7 0.7)
					(thickness 0.15)
				)
				(justify left bottom mirror)
			)
		)
		(fp_text user "${REFERENCE}"
			(at -0.95 -3.168 90)
			(layer "B.Fab")
			(effects
				(font
					(size 0.7 0.7)
					(thickness 0.15)
				)
				(justify left bottom mirror)
			)
		)
		(pad "1" smd roundrect
			(at -0.48 0 270)
			(size 0.59 0.64)
			(layers "B.Cu" "B.Mask" "B.Paste")
			(roundrect_rratio 0.25)
			(net 853 "/I2C_{SYS}.SCL")
			(pintype "passive")
		)
		(pad "2" smd roundrect
			(at 0.48 0 270)
			(size 0.59 0.64)
			(layers "B.Cu" "B.Mask" "B.Paste")
			(roundrect_rratio 0.25)
			(net 945 "/USB Debug, PD/DEBUG_SCL")
			(pintype "passive")
		)
	)
)
